(kicad_pcb
	(version 20221018)
	(generator pcbnew)
	(general
    (thickness 1.62)
  )
	(paper "A4")
	(title_block
    (title "ECP5 - Datacenter Secure Control Module (DC-SCM)")
    (date "2024-07-01")
    (rev "1.2.1")
		(comment 9 "footprints 443-449 of 506")
	)
	(layers
    (0 "F.Cu" signal)
    (1 "In1.Cu" power)
    (2 "In2.Cu" signal)
    (3 "In3.Cu" power)
    (4 "In4.Cu" power)
    (5 "In5.Cu" signal)
    (6 "In6.Cu" power)
    (31 "B.Cu" signal)
    (32 "B.Adhes" user "B.Adhesive")
    (33 "F.Adhes" user "F.Adhesive")
    (34 "B.Paste" user)
    (35 "F.Paste" user)
    (36 "B.SilkS" user "B.Silkscreen")
    (37 "F.SilkS" user "F.Silkscreen")
    (38 "B.Mask" user)
    (39 "F.Mask" user)
    (40 "Dwgs.User" user "User.Drawings")
    (41 "Cmts.User" user "User.Comments")
    (42 "Eco1.User" user "User.Eco1")
    (43 "Eco2.User" user "User.Eco2")
    (44 "Edge.Cuts" user)
    (45 "Margin" user)
    (46 "B.CrtYd" user "B.Courtyard")
    (47 "F.CrtYd" user "F.Courtyard")
    (48 "B.Fab" user)
    (49 "F.Fab" user)
  )
	(footprint "antmicro-footprints:C_0402_1005Metric" (layer "B.Cu")
    (at 85.8 101.6 180)
    (descr "Capacitor SMD 0402")
    (tags "capacitor SMD 0402")
    (property "Author" "Antmicro")
    (property "Dielectric" "X5R")
    (property "License" "Apache-2.0")
    (property "MPN" "GRM155R61H104KE14D")
    (property "Manufacturer" "Murata")
    (property "Public" "False")
    (property "Sheetfile" "interfaces.kicad_sch")
    (property "Sheetname" "Interfaces")
    (property "Val" "100n")
    (property "Voltage" "50V")
    (property "ki_description" "SMD Multilayer Ceramic Capacitor, 0.1 µF, 50 V, 0402 [1005 Metric], ± 10%, X5R, GRM Series")
    (property "ki_keywords" "0402, SMT, CAPACITOR, PASSIVE, CERAMIC, MLCC")
    (attr smd)
    (fp_text reference "C247" (at 0.066667 9.14625) (layer "B.SilkS")
        (effects (font (size 0.7 0.7) (thickness 0.127)) (justify mirror))
    )
    (fp_text value "C_100n_0402" (at 0 -1.17) (layer "B.Fab")
        (effects (font (size 1 1) (thickness 0.15)) (justify mirror))
    )
    (fp_text user "Author: Antmicro" (at -0.939 -3.399) (layer "B.Fab") hide
        (effects (font (size 0.7 0.7) (thickness 0.15)) (justify left bottom mirror))
    )
    (fp_text user "${REFERENCE}" (at 0 0) (layer "B.Fab")
        (effects (font (size 0.25 0.25) (thickness 0.04)) (justify mirror))
    )
    (fp_text user "License: Apache-2.0" (at -0.939 -5.799) (layer "B.Fab") hide
        (effects (font (size 0.7 0.7) (thickness 0.15)) (justify left bottom mirror))
    )
    (fp_rect (start -0.925 0.47) (end 0.925 -0.47)
      (stroke (width 0.05) (type default)) (fill none) (layer "B.CrtYd"))
    (fp_line (start -0.494 -0.248) (end -0.494 0.25)
      (stroke (width 0.15) (type solid)) (layer "B.Fab"))
    (fp_line (start -0.494 0.25) (end 0.504 0.25)
      (stroke (width 0.15) (type solid)) (layer "B.Fab"))
    (fp_line (start 0.504 -0.248) (end -0.494 -0.248)
      (stroke (width 0.15) (type solid)) (layer "B.Fab"))
    (fp_line (start 0.504 0.25) (end 0.504 -0.248)
      (stroke (width 0.15) (type solid)) (layer "B.Fab"))
    (pad "1" smd roundrect (at -0.48 0 180) (size 0.59 0.64) (layers "B.Cu" "B.Paste" "B.Mask") (roundrect_rratio 0.25)
      (net 1 "GND") (pintype "passive"))
    (pad "2" smd roundrect (at 0.48 0 180) (size 0.59 0.64) (layers "B.Cu" "B.Paste" "B.Mask") (roundrect_rratio 0.25)
      (net 2 "VCC3V3") (pintype "passive"))
  )
	(footprint "antmicro-footprints:R_0402_1005Metric" (layer "B.Cu")
    (at 94.575 95.05 180)
    (descr "Resistor SMD 0402")
    (tags "resistor SMD 0402")
    (property "Author" "Antmicro")
    (property "License" "Apache-2.0")
    (property "MPN" "CR0402-FX-4702GLF")
    (property "Manufacturer" "Bourns")
    (property "Public" "False")
    (property "Sheetfile" "interfaces.kicad_sch")
    (property "Sheetname" "Interfaces")
    (property "Tolerance" "1%")
    (property "Val" "47k")
    (property "ki_description" "SMD Chip Resistor, 47 kohm, ± 1%, 62.5 mW, 0402 [1005 Metric], Thick Film, General Purpose")
    (property "ki_keywords" "0402, SMT, RESISTOR, PASSIVE")
    (attr smd)
    (fp_text reference "R67" (at 0.025 -7.55) (layer "B.SilkS")
        (effects (font (size 0.7 0.7) (thickness 0.127)) (justify mirror))
    )
    (fp_text value "R_47k_0402" (at 0 -1.17) (layer "B.Fab")
        (effects (font (size 1 1) (thickness 0.15)) (justify mirror))
    )
    (fp_text user "License: Apache-2.0" (at -0.95 -5.169) (layer "B.Fab") hide
        (effects (font (size 0.7 0.7) (thickness 0.15)) (justify left bottom mirror))
    )
    (fp_text user "Author: Antmicro" (at -0.95 -4.169) (layer "B.Fab") hide
        (effects (font (size 0.7 0.7) (thickness 0.15)) (justify left bottom mirror))
    )
    (fp_text user "${REFERENCE}" (at 0 0) (layer "B.Fab")
        (effects (font (size 0.25 0.25) (thickness 0.04)) (justify mirror))
    )
    (fp_rect (start -0.925 0.47) (end 0.925 -0.47)
      (stroke (width 0.05) (type default)) (fill none) (layer "B.CrtYd"))
    (fp_rect (start -0.5 0.25) (end 0.5 -0.25)
      (stroke (width 0.15) (type solid)) (fill none) (layer "B.Fab"))
    (pad "1" smd roundrect (at -0.48 0 180) (size 0.59 0.64) (layers "B.Cu" "B.Paste" "B.Mask") (roundrect_rratio 0.25)
      (net 2 "VCC3V3") (pintype "passive"))
    (pad "2" smd roundrect (at 0.48 0 180) (size 0.59 0.64) (layers "B.Cu" "B.Paste" "B.Mask") (roundrect_rratio 0.25)
      (net 285 "MMC_DAT6") (pintype "passive"))
  )
	(footprint "antmicro-footprints:R_0402_1005Metric" (layer "B.Cu")
    (at 94.55 101.6 180)
    (descr "Resistor SMD 0402")
    (tags "resistor SMD 0402")
    (property "Author" "Antmicro")
    (property "License" "Apache-2.0")
    (property "MPN" "CR0402-FX-4702GLF")
    (property "Manufacturer" "Bourns")
    (property "Public" "False")
    (property "Sheetfile" "interfaces.kicad_sch")
    (property "Sheetname" "Interfaces")
    (property "Tolerance" "1%")
    (property "Val" "47k")
    (property "ki_description" "SMD Chip Resistor, 47 kohm, ± 1%, 62.5 mW, 0402 [1005 Metric], Thick Film, General Purpose")
    (property "ki_keywords" "0402, SMT, RESISTOR, PASSIVE")
    (attr smd)
    (fp_text reference "R62" (at 0 -6.8) (layer "B.SilkS")
        (effects (font (size 0.7 0.7) (thickness 0.127)) (justify mirror))
    )
    (fp_text value "R_47k_0402" (at 0 -1.17) (layer "B.Fab")
        (effects (font (size 1 1) (thickness 0.15)) (justify mirror))
    )
    (fp_text user "${REFERENCE}" (at 0 0) (layer "B.Fab")
        (effects (font (size 0.25 0.25) (thickness 0.04)) (justify mirror))
    )
    (fp_text user "Author: Antmicro" (at -0.95 -4.169) (layer "B.Fab") hide
        (effects (font (size 0.7 0.7) (thickness 0.15)) (justify left bottom mirror))
    )
    (fp_text user "License: Apache-2.0" (at -0.95 -5.169) (layer "B.Fab") hide
        (effects (font (size 0.7 0.7) (thickness 0.15)) (justify left bottom mirror))
    )
    (fp_rect (start -0.925 0.47) (end 0.925 -0.47)
      (stroke (width 0.05) (type default)) (fill none) (layer "B.CrtYd"))
    (fp_rect (start -0.5 0.25) (end 0.5 -0.25)
      (stroke (width 0.15) (type solid)) (fill none) (layer "B.Fab"))
    (pad "1" smd roundrect (at -0.48 0 180) (size 0.59 0.64) (layers "B.Cu" "B.Paste" "B.Mask") (roundrect_rratio 0.25)
      (net 2 "VCC3V3") (pintype "passive"))
    (pad "2" smd roundrect (at 0.48 0 180) (size 0.59 0.64) (layers "B.Cu" "B.Paste" "B.Mask") (roundrect_rratio 0.25)
      (net 280 "MMC_DAT1") (pintype "passive"))
  )
	(footprint "antmicro-footprints:SOT-23-3" (layer "B.Cu")
    (at 67.25 89.1 180)
    (property "Author" "Antmicro")
    (property "License" "Apache-2.0")
    (property "MPN" "2N7002")
    (property "Manufacturer" "ON Semiconductor")
    (property "Sheetfile" "power-supply.kicad_sch")
    (property "Sheetname" "Power supply")
    (property "ki_description" "Power MOSFET, N Channel, 60 V, 115 mA, 1.2 ohm, SOT-23, Surface Mount")
    (property "ki_keywords" "SMT, TRANSISTOR, SEMICONDUCTOR, NMOS")
    (attr smd)
    (fp_text reference "Q16" (at -1.8 1.85 180) (layer "B.SilkS")
        (effects (font (size 0.7 0.7) (thickness 0.127)) (justify mirror))
    )
    (fp_text value "2N7002" (at 0.025 -3.25 180) (layer "B.Fab")
        (effects (font (size 1 1) (thickness 0.15)) (justify mirror))
    )
    (fp_text user "Author: Antmicro" (at -1.837 -5.3) (layer "B.Fab") hide
        (effects (font (size 0.7 0.7) (thickness 0.15)) (justify left bottom mirror))
    )
    (fp_text user "${REFERENCE}" (at -0.125 -0.15 180) (layer "B.Fab")
        (effects (font (size 0.25 0.25) (thickness 0.05)) (justify mirror))
    )
    (fp_text user "License: Apache-2.0" (at -1.8 -6.8) (layer "B.Fab") hide
        (effects (font (size 0.7 0.7) (thickness 0.15)) (justify left bottom mirror))
    )
    (fp_line (start -1.45 1.35) (end -0.85 1.35)
      (stroke (width 0.15) (type solid)) (layer "B.SilkS"))
    (fp_line (start -0.85 1.35) (end -0.7 1.5)
      (stroke (width 0.15) (type solid)) (layer "B.SilkS"))
    (fp_line (start -0.7 -1.5) (end -0.7 -1.35)
      (stroke (width 0.15) (type solid)) (layer "B.SilkS"))
    (fp_line (start 0.7 -1.5) (end -0.7 -1.5)
      (stroke (width 0.15) (type solid)) (layer "B.SilkS"))
    (fp_line (start 0.7 -0.4) (end 0.7 -1.5)
      (stroke (width 0.15) (type solid)) (layer "B.SilkS"))
    (fp_line (start 0.7 0.4) (end 0.7 1.5)
      (stroke (width 0.15) (type solid)) (layer "B.SilkS"))
    (fp_line (start 0.7 1.5) (end -0.7 1.5)
      (stroke (width 0.15) (type solid)) (layer "B.SilkS"))
    (fp_line (start -1.75 -1.4) (end -1.75 -0.5)
      (stroke (width 0.05) (type solid)) (layer "B.CrtYd"))
    (fp_line (start -1.75 -0.5) (end -0.85 -0.5)
      (stroke (width 0.05) (type solid)) (layer "B.CrtYd"))
    (fp_line (start -1.75 0.5) (end -1.75 1.4)
      (stroke (width 0.05) (type solid)) (layer "B.CrtYd"))
    (fp_line (start -0.9 1.4) (end -1.75 1.4)
      (stroke (width 0.05) (type solid)) (layer "B.CrtYd"))
    (fp_line (start -0.9 1.6) (end -0.9 1.4)
      (stroke (width 0.05) (type solid)) (layer "B.CrtYd"))
    (fp_line (start -0.9 1.6) (end 0.825 1.6)
      (stroke (width 0.05) (type solid)) (layer "B.CrtYd"))
    (fp_line (start -0.85 -1.65) (end -0.85 -1.4)
      (stroke (width 0.05) (type solid)) (layer "B.CrtYd"))
    (fp_line (start -0.85 -1.4) (end -1.75 -1.4)
      (stroke (width 0.05) (type solid)) (layer "B.CrtYd"))
    (fp_line (start -0.85 -0.5) (end -0.85 0.5)
      (stroke (width 0.05) (type solid)) (layer "B.CrtYd"))
    (fp_line (start -0.85 0.5) (end -1.75 0.5)
      (stroke (width 0.05) (type solid)) (layer "B.CrtYd"))
    (fp_line (start 0.825 0.45) (end 1.75 0.45)
      (stroke (width 0.05) (type solid)) (layer "B.CrtYd"))
    (fp_line (start 0.825 1.6) (end 0.825 0.45)
      (stroke (width 0.05) (type solid)) (layer "B.CrtYd"))
    (fp_line (start 0.85 -1.65) (end -0.85 -1.65)
      (stroke (width 0.05) (type solid)) (layer "B.CrtYd"))
    (fp_line (start 0.85 -0.45) (end 0.85 -1.65)
      (stroke (width 0.05) (type solid)) (layer "B.CrtYd"))
    (fp_line (start 1.75 -0.45) (end 0.85 -0.45)
      (stroke (width 0.05) (type solid)) (layer "B.CrtYd"))
    (fp_line (start 1.75 0.45) (end 1.75 -0.45)
      (stroke (width 0.05) (type solid)) (layer "B.CrtYd"))
    (fp_line (start -0.712 -1.519) (end 0.688 -1.519)
      (stroke (width 0.15) (type solid)) (layer "B.Fab"))
    (fp_line (start -0.712 1.325) (end -0.712 -1.523)
      (stroke (width 0.15) (type solid)) (layer "B.Fab"))
    (fp_line (start -0.437 1.526) (end -0.712 1.325)
      (stroke (width 0.15) (type solid)) (layer "B.Fab"))
    (fp_line (start -0.437 1.526) (end 0.688 1.526)
      (stroke (width 0.15) (type solid)) (layer "B.Fab"))
    (fp_line (start 0.688 -1.519) (end 0.688 1.52)
      (stroke (width 0.15) (type solid)) (layer "B.Fab"))
    (pad "1" smd roundrect (at -1.1 0.951 180) (size 1 0.6) (layers "B.Cu" "B.Paste" "B.Mask") (roundrect_rratio 0.15)
      (net 224 "/Power supply/1V35_PG") (pinfunction "G") (pintype "passive"))
    (pad "2" smd roundrect (at -1.1 -0.949 180) (size 1 0.6) (layers "B.Cu" "B.Paste" "B.Mask") (roundrect_rratio 0.15)
      (net 1 "GND") (pinfunction "S") (pintype "passive"))
    (pad "3" smd roundrect (at 1.1 0.0005 180) (size 1 0.6) (layers "B.Cu" "B.Paste" "B.Mask") (roundrect_rratio 0.15)
      (net 400 "Net-(Q16-D)") (pinfunction "D") (pintype "passive"))
  )
	(footprint "antmicro-footprints:C_0402_1005Metric" (layer "B.Cu")
    (at 101.75 113.8 90)
    (descr "Capacitor SMD 0402")
    (tags "capacitor SMD 0402")
    (property "Author" "Antmicro")
    (property "Dielectric" "")
    (property "License" "Apache-2.0")
    (property "MPN" "C1005X5R1E474M050BB")
    (property "Manufacturer" "TDK")
    (property "Public" "False")
    (property "Sheetfile" "fpga-banks.kicad_sch")
    (property "Sheetname" "FPGA banks")
    (property "Val" "470n")
    (property "Voltage" "")
    (property "ki_description" "SMD Multilayer Ceramic Capacitor, 0.47 µF, 25 V, 0402 [1005 Metric], ± 20%, X5R, C")
    (property "ki_keywords" "0402, SMT, CAPACITOR, PASSIVE, CERAMIC, MLCC")
    (attr smd)
    (fp_text reference "C205" (at 2.45 0 90) (layer "B.SilkS")
        (effects (font (size 0.7 0.7) (thickness 0.127)) (justify mirror))
    )
    (fp_text value "C_470n_0402" (at 0 -1.17 90) (layer "B.Fab")
        (effects (font (size 1 1) (thickness 0.15)) (justify mirror))
    )
    (fp_text user "License: Apache-2.0" (at -0.939 -5.799 270) (layer "B.Fab") hide
        (effects (font (size 0.7 0.7) (thickness 0.15)) (justify left bottom mirror))
    )
    (fp_text user "${REFERENCE}" (at 0 0 90) (layer "B.Fab")
        (effects (font (size 0.25 0.25) (thickness 0.04)) (justify mirror))
    )
    (fp_text user "Author: Antmicro" (at -0.939 -3.399 270) (layer "B.Fab") hide
        (effects (font (size 0.7 0.7) (thickness 0.15)) (justify left bottom mirror))
    )
    (fp_rect (start -0.925 0.47) (end 0.925 -0.47)
      (stroke (width 0.05) (type default)) (fill none) (layer "B.CrtYd"))
    (fp_line (start -0.494 -0.248) (end -0.494 0.25)
      (stroke (width 0.15) (type solid)) (layer "B.Fab"))
    (fp_line (start -0.494 0.25) (end 0.504 0.25)
      (stroke (width 0.15) (type solid)) (layer "B.Fab"))
    (fp_line (start 0.504 -0.248) (end -0.494 -0.248)
      (stroke (width 0.15) (type solid)) (layer "B.Fab"))
    (fp_line (start 0.504 0.25) (end 0.504 -0.248)
      (stroke (width 0.15) (type solid)) (layer "B.Fab"))
    (pad "1" smd roundrect (at -0.48 0 90) (size 0.59 0.64) (layers "B.Cu" "B.Paste" "B.Mask") (roundrect_rratio 0.25)
      (net 2 "VCC3V3") (pintype "passive"))
    (pad "2" smd roundrect (at 0.48 0 90) (size 0.59 0.64) (layers "B.Cu" "B.Paste" "B.Mask") (roundrect_rratio 0.25)
      (net 1 "GND") (pintype "passive"))
  )
	(footprint "antmicro-footprints:C_0402_1005Metric" (layer "B.Cu")
    (at 114.3 83.45 180)
    (descr "Capacitor SMD 0402")
    (tags "capacitor SMD 0402")
    (property "Author" "Antmicro")
    (property "Dielectric" "X5R")
    (property "License" "Apache-2.0")
    (property "MPN" "GRM155R61H104KE14D")
    (property "Manufacturer" "Murata")
    (property "Public" "False")
    (property "Sheetfile" "ethernet.kicad_sch")
    (property "Sheetname" "Ethernet")
    (property "Val" "100n")
    (property "Voltage" "50V")
    (property "ki_description" "SMD Multilayer Ceramic Capacitor, 0.1 µF, 50 V, 0402 [1005 Metric], ± 10%, X5R, GRM Series")
    (property "ki_keywords" "0402, SMT, CAPACITOR, PASSIVE, CERAMIC, MLCC")
    (attr smd)
    (fp_text reference "C27" (at -0.09 -1.045) (layer "B.SilkS")
        (effects (font (size 0.7 0.7) (thickness 0.127)) (justify mirror))
    )
    (fp_text value "C_100n_0402" (at 0 -1.17) (layer "B.Fab")
        (effects (font (size 1 1) (thickness 0.15)) (justify mirror))
    )
    (fp_text user "License: Apache-2.0" (at -0.939 -5.799) (layer "B.Fab") hide
        (effects (font (size 0.7 0.7) (thickness 0.15)) (justify left bottom mirror))
    )
    (fp_text user "${REFERENCE}" (at 0 0) (layer "B.Fab")
        (effects (font (size 0.25 0.25) (thickness 0.04)) (justify mirror))
    )
    (fp_text user "Author: Antmicro" (at -0.939 -3.399) (layer "B.Fab") hide
        (effects (font (size 0.7 0.7) (thickness 0.15)) (justify left bottom mirror))
    )
    (fp_rect (start -0.925 0.47) (end 0.925 -0.47)
      (stroke (width 0.05) (type default)) (fill none) (layer "B.CrtYd"))
    (fp_line (start -0.494 -0.248) (end -0.494 0.25)
      (stroke (width 0.15) (type solid)) (layer "B.Fab"))
    (fp_line (start -0.494 0.25) (end 0.504 0.25)
      (stroke (width 0.15) (type solid)) (layer "B.Fab"))
    (fp_line (start 0.504 -0.248) (end -0.494 -0.248)
      (stroke (width 0.15) (type solid)) (layer "B.Fab"))
    (fp_line (start 0.504 0.25) (end 0.504 -0.248)
      (stroke (width 0.15) (type solid)) (layer "B.Fab"))
    (pad "1" smd roundrect (at -0.48 0 180) (size 0.59 0.64) (layers "B.Cu" "B.Paste" "B.Mask") (roundrect_rratio 0.25)
      (net 1 "GND") (pintype "passive"))
    (pad "2" smd roundrect (at 0.48 0 180) (size 0.59 0.64) (layers "B.Cu" "B.Paste" "B.Mask") (roundrect_rratio 0.25)
      (net 7 "Net-(J1-TRCT1)") (pintype "passive"))
  )
	(footprint "antmicro-footprints:C_0402_1005Metric" (layer "B.Cu")
    (at 114.3 82.45 180)
    (descr "Capacitor SMD 0402")
    (tags "capacitor SMD 0402")
    (property "Author" "Antmicro")
    (property "Dielectric" "X5R")
    (property "License" "Apache-2.0")
    (property "MPN" "GRM155R61H104KE14D")
    (property "Manufacturer" "Murata")
    (property "Public" "False")
    (property "Sheetfile" "ethernet.kicad_sch")
    (property "Sheetname" "Ethernet")
    (property "Val" "100n")
    (property "Voltage" "50V")
    (property "ki_description" "SMD Multilayer Ceramic Capacitor, 0.1 µF, 50 V, 0402 [1005 Metric], ± 10%, X5R, GRM Series")
    (property "ki_keywords" "0402, SMT, CAPACITOR, PASSIVE, CERAMIC, MLCC")
    (attr smd)
    (fp_text reference "C28" (at -0.42 0.945) (layer "B.SilkS")
        (effects (font (size 0.7 0.7) (thickness 0.127)) (justify mirror))
    )
    (fp_text value "C_100n_0402" (at 0 -1.17) (layer "B.Fab")
        (effects (font (size 1 1) (thickness 0.15)) (justify mirror))
    )
    (fp_text user "${REFERENCE}" (at 0 0 90) (layer "B.Fab")
        (effects (font (size 0.25 0.25) (thickness 0.04)) (justify mirror))
    )
    (fp_text user "License: Apache-2.0" (at -0.939 -5.799) (layer "B.Fab") hide
        (effects (font (size 0.7 0.7) (thickness 0.15)) (justify left bottom mirror))
    )
    (fp_text user "Author: Antmicro" (at -0.939 -3.399) (layer "B.Fab") hide
        (effects (font (size 0.7 0.7) (thickness 0.15)) (justify left bottom mirror))
    )
    (fp_rect (start -0.925 0.47) (end 0.925 -0.47)
      (stroke (width 0.05) (type default)) (fill none) (layer "B.CrtYd"))
    (fp_line (start -0.494 -0.248) (end -0.494 0.25)
      (stroke (width 0.15) (type solid)) (layer "B.Fab"))
    (fp_line (start -0.494 0.25) (end 0.504 0.25)
      (stroke (width 0.15) (type solid)) (layer "B.Fab"))
    (fp_line (start 0.504 -0.248) (end -0.494 -0.248)
      (stroke (width 0.15) (type solid)) (layer "B.Fab"))
    (fp_line (start 0.504 0.25) (end 0.504 -0.248)
      (stroke (width 0.15) (type solid)) (layer "B.Fab"))
    (pad "1" smd roundrect (at -0.48 0 180) (size 0.59 0.64) (layers "B.Cu" "B.Paste" "B.Mask") (roundrect_rratio 0.25)
      (net 1 "GND") (pintype "passive"))
    (pad "2" smd roundrect (at 0.48 0 180) (size 0.59 0.64) (layers "B.Cu" "B.Paste" "B.Mask") (roundrect_rratio 0.25)
      (net 8 "Net-(J1-TRCT2)") (pintype "passive"))
  )
)
